(kicad_pcb
	(version 20221018)
	(generator pcbnew)
	(general
    (thickness 1.62)
  )
	(paper "A4")
	(title_block
    (title "ECP5 - Datacenter Secure Control Module (DC-SCM)")
    (date "2024-07-01")
    (rev "1.2.1")
		(comment 9 "footprint 190 of 506 (U6), pads 1-100 of 100")
	)
	(layers
    (0 "F.Cu" signal)
    (1 "In1.Cu" power)
    (2 "In2.Cu" signal)
    (3 "In3.Cu" power)
    (4 "In4.Cu" power)
    (5 "In5.Cu" signal)
    (6 "In6.Cu" power)
    (31 "B.Cu" signal)
    (32 "B.Adhes" user "B.Adhesive")
    (33 "F.Adhes" user "F.Adhesive")
    (34 "B.Paste" user)
    (35 "F.Paste" user)
    (36 "B.SilkS" user "B.Silkscreen")
    (37 "F.SilkS" user "F.Silkscreen")
    (38 "B.Mask" user)
    (39 "F.Mask" user)
    (40 "Dwgs.User" user "User.Drawings")
    (41 "Cmts.User" user "User.Comments")
    (42 "Eco1.User" user "User.Eco1")
    (43 "Eco2.User" user "User.Eco2")
    (44 "Edge.Cuts" user)
    (45 "Margin" user)
    (46 "B.CrtYd" user "B.Courtyard")
    (47 "F.CrtYd" user "F.Courtyard")
    (48 "B.Fab" user)
    (49 "F.Fab" user)
  )
	(footprint "antmicro-footprints:BGA-170-100_18x14mm_Layout17x10_P1mm"
    (layer "F.Cu")
    (at 88.2 98.05 90)
    (descr "Uses depopulated JEDEC-MO-304B")
    (property "Author" "Antmicro")
    (property "License" "Apache-2.0")
    (property "MANUFACTURER" "Micron")
    (property "MPN" "MTFC16GAPALNA-AIT")
    (property "Manufacturer" "Micron Technology")
    (property "Package" "100-ball TBGA 14x18")
    (property "Sheetfile" "interfaces.kicad_sch")
    (property "Sheetname" "Interfaces")
    (property "ki_description" "Managed NAND Flash Serial e-MMC 3.3V 128G-bit 128G/32G/16G x 1/4-bit/8-bit Automotive AEC-Q100 100-Pin TBGA Tray")
    (property "ki_keywords" "SMT, FLASH, IC")
    (attr smd)
    (fp_text reference "U6" (at -8.075 -8 180) (layer "F.SilkS")
        (effects (font (size 0.7 0.7) (thickness 0.127)))
    )
    (fp_text value "MTFC16GAPALNA-AIT" (at 16.305925 13.334495 90) (layer "F.Fab")
        (effects (font (size 1.339362 1.339362) (thickness 0.015)))
    )
    (pad "A1" smd circle (at -4.5 -8 90) (size 0.37 0.37) (layers "F.Cu" "F.Paste" "F.Mask")
      (net 442 "unconnected-(U6-NC-PadA1)") (pinfunction "NC") (pintype "no_connect"))
    (pad "A2" smd circle (at -3.5 -8 90) (size 0.37 0.37) (layers "F.Cu" "F.Paste" "F.Mask")
      (net 443 "unconnected-(U6-NC-PadA2)") (pinfunction "NC") (pintype "no_connect"))
    (pad "A9" smd circle (at 3.499 -8 90) (size 0.37 0.37) (layers "F.Cu" "F.Paste" "F.Mask")
      (net 444 "unconnected-(U6-NC-PadA9)") (pinfunction "NC") (pintype "no_connect"))
    (pad "A10" smd circle (at 4.499 -8 90) (size 0.37 0.37) (layers "F.Cu" "F.Paste" "F.Mask")
      (net 445 "unconnected-(U6-NC-PadA10)") (pinfunction "NC") (pintype "no_connect"))
    (pad "B1" smd circle (at -4.5 -7 90) (size 0.37 0.37) (layers "F.Cu" "F.Paste" "F.Mask")
      (net 446 "unconnected-(U6-NC-PadB1)") (pinfunction "NC") (pintype "no_connect"))
    (pad "B10" smd circle (at 4.499 -7 90) (size 0.37 0.37) (layers "F.Cu" "F.Paste" "F.Mask")
      (net 447 "unconnected-(U6-NC-PadB10)") (pinfunction "NC") (pintype "no_connect"))
    (pad "D2" smd circle (at -3.5 -5 90) (size 0.37 0.37) (layers "F.Cu" "F.Paste" "F.Mask")
      (net 448 "unconnected-(U6-VSF1-PadD2)") (pinfunction "VSF1") (pintype "no_connect"))
    (pad "D3" smd circle (at -2.5 -5 90) (size 0.37 0.37) (layers "F.Cu" "F.Paste" "F.Mask")
      (net 449 "unconnected-(U6-VSF2-PadD3)") (pinfunction "VSF2") (pintype "no_connect"))
    (pad "D4" smd circle (at -1.5 -5 90) (size 0.37 0.37) (layers "F.Cu" "F.Paste" "F.Mask")
      (net 450 "unconnected-(U6-VSF3-PadD4)") (pinfunction "VSF3") (pintype "no_connect"))
    (pad "D5" smd circle (at -0.5 -5 90) (size 0.37 0.37) (layers "F.Cu" "F.Paste" "F.Mask")
      (net 451 "unconnected-(U6-VSF4-PadD5)") (pinfunction "VSF4") (pintype "no_connect"))
    (pad "D6" smd circle (at 0.499 -5 90) (size 0.37 0.37) (layers "F.Cu" "F.Paste" "F.Mask")
      (net 452 "unconnected-(U6-VSF5-PadD6)") (pinfunction "VSF5") (pintype "no_connect"))
    (pad "D7" smd circle (at 1.499 -5 90) (size 0.37 0.37) (layers "F.Cu" "F.Paste" "F.Mask")
      (net 453 "unconnected-(U6-VSF6-PadD7)") (pinfunction "VSF6") (pintype "no_connect"))
    (pad "D8" smd circle (at 2.499 -5 90) (size 0.37 0.37) (layers "F.Cu" "F.Paste" "F.Mask")
      (net 454 "unconnected-(U6-VSF7-PadD8)") (pinfunction "VSF7") (pintype "no_connect"))
    (pad "D9" smd circle (at 3.499 -5 90) (size 0.37 0.37) (layers "F.Cu" "F.Paste" "F.Mask")
      (net 455 "unconnected-(U6-VSF8-PadD9)") (pinfunction "VSF8") (pintype "no_connect"))
    (pad "E2" smd circle (at -3.5 -4 90) (size 0.37 0.37) (layers "F.Cu" "F.Paste" "F.Mask")
      (net 456 "unconnected-(U6-RFU-PadE2)") (pinfunction "RFU") (pintype "no_connect"))
    (pad "E3" smd circle (at -2.5 -4 90) (size 0.37 0.37) (layers "F.Cu" "F.Paste" "F.Mask")
      (net 457 "unconnected-(U6-RFU-PadE3)") (pinfunction "RFU") (pintype "no_connect"))
    (pad "E4" smd circle (at -1.5 -4 90) (size 0.37 0.37) (layers "F.Cu" "F.Paste" "F.Mask")
      (net 219 "Net-(U6-VDDIM)") (pinfunction "VDDIM") (pintype "power_in"))
    (pad "E5" smd circle (at -0.5 -4 90) (size 0.37 0.37) (layers "F.Cu" "F.Paste" "F.Mask")
      (net 458 "unconnected-(U6-RFU-PadE5)") (pinfunction "RFU") (pintype "no_connect"))
    (pad "E6" smd circle (at 0.499 -4 90) (size 0.37 0.37) (layers "F.Cu" "F.Paste" "F.Mask")
      (net 459 "unconnected-(U6-RFU-PadE6)") (pinfunction "RFU") (pintype "no_connect"))
    (pad "E7" smd circle (at 1.499 -4 90) (size 0.37 0.37) (layers "F.Cu" "F.Paste" "F.Mask")
      (net 460 "unconnected-(U6-RFU-PadE7)") (pinfunction "RFU") (pintype "no_connect"))
    (pad "E8" smd circle (at 2.499 -4 90) (size 0.37 0.37) (layers "F.Cu" "F.Paste" "F.Mask")
      (net 461 "unconnected-(U6-RFU-PadE8)") (pinfunction "RFU") (pintype "no_connect"))
    (pad "E9" smd circle (at 3.499 -4 90) (size 0.37 0.37) (layers "F.Cu" "F.Paste" "F.Mask")
      (net 462 "unconnected-(U6-RFU-PadE9)") (pinfunction "RFU") (pintype "no_connect"))
    (pad "F2" smd circle (at -3.5 -3 90) (size 0.37 0.37) (layers "F.Cu" "F.Paste" "F.Mask")
      (net 2 "VCC3V3") (pinfunction "VCC") (pintype "power_in"))
    (pad "F3" smd circle (at -2.5 -3 90) (size 0.37 0.37) (layers "F.Cu" "F.Paste" "F.Mask")
      (net 2 "VCC3V3") (pinfunction "VCC") (pintype "passive"))
    (pad "F4" smd circle (at -1.5 -3 90) (size 0.37 0.37) (layers "F.Cu" "F.Paste" "F.Mask")
      (net 2 "VCC3V3") (pinfunction "VCC") (pintype "passive"))
    (pad "F5" smd circle (at -0.5 -3 90) (size 0.37 0.37) (layers "F.Cu" "F.Paste" "F.Mask")
      (net 2 "VCC3V3") (pinfunction "VCC") (pintype "passive"))
    (pad "F6" smd circle (at 0.499 -3 90) (size 0.37 0.37) (layers "F.Cu" "F.Paste" "F.Mask")
      (net 2 "VCC3V3") (pinfunction "VCC") (pintype "passive"))
    (pad "F7" smd circle (at 1.499 -3 90) (size 0.37 0.37) (layers "F.Cu" "F.Paste" "F.Mask")
      (net 2 "VCC3V3") (pinfunction "VCC") (pintype "passive"))
    (pad "F8" smd circle (at 2.499 -3 90) (size 0.37 0.37) (layers "F.Cu" "F.Paste" "F.Mask")
      (net 2 "VCC3V3") (pinfunction "VCC") (pintype "passive"))
    (pad "F9" smd circle (at 3.499 -3 90) (size 0.37 0.37) (layers "F.Cu" "F.Paste" "F.Mask")
      (net 2 "VCC3V3") (pinfunction "VCC") (pintype "passive"))
    (pad "G2" smd circle (at -3.5 -2 90) (size 0.37 0.37) (layers "F.Cu" "F.Paste" "F.Mask")
      (net 1 "GND") (pinfunction "VSS") (pintype "power_in"))
    (pad "G3" smd circle (at -2.5 -2 90) (size 0.37 0.37) (layers "F.Cu" "F.Paste" "F.Mask")
      (net 1 "GND") (pinfunction "VSS") (pintype "passive"))
    (pad "G4" smd circle (at -1.5 -2 90) (size 0.37 0.37) (layers "F.Cu" "F.Paste" "F.Mask")
      (net 1 "GND") (pinfunction "VSS") (pintype "passive"))
    (pad "G5" smd circle (at -0.5 -2 90) (size 0.37 0.37) (layers "F.Cu" "F.Paste" "F.Mask")
      (net 1 "GND") (pinfunction "VSS") (pintype "passive"))
    (pad "G6" smd circle (at 0.499 -2 90) (size 0.37 0.37) (layers "F.Cu" "F.Paste" "F.Mask")
      (net 1 "GND") (pinfunction "VSS") (pintype "passive"))
    (pad "G7" smd circle (at 1.499 -2 90) (size 0.37 0.37) (layers "F.Cu" "F.Paste" "F.Mask")
      (net 1 "GND") (pinfunction "VSS") (pintype "passive"))
    (pad "G8" smd circle (at 2.499 -2 90) (size 0.37 0.37) (layers "F.Cu" "F.Paste" "F.Mask")
      (net 1 "GND") (pinfunction "VSS") (pintype "passive"))
    (pad "G9" smd circle (at 3.499 -2 90) (size 0.37 0.37) (layers "F.Cu" "F.Paste" "F.Mask")
      (net 1 "GND") (pinfunction "VSS") (pintype "passive"))
    (pad "H2" smd circle (at -3.5 -1 90) (size 0.37 0.37) (layers "F.Cu" "F.Paste" "F.Mask")
      (net 1 "GND") (pinfunction "VSSQ") (pintype "power_in"))
    (pad "H3" smd circle (at -2.5 -1 90) (size 0.37 0.37) (layers "F.Cu" "F.Paste" "F.Mask")
      (net 2 "VCC3V3") (pinfunction "VCCQ") (pintype "power_in"))
    (pad "H4" smd circle (at -1.5 -1 90) (size 0.37 0.37) (layers "F.Cu" "F.Paste" "F.Mask")
      (net 463 "unconnected-(U6-RFU-PadH4)") (pinfunction "RFU") (pintype "no_connect"))
    (pad "H5" smd circle (at -0.5 -1 90) (size 0.37 0.37) (layers "F.Cu" "F.Paste" "F.Mask")
      (net 464 "unconnected-(U6-RFU-PadH5)") (pinfunction "RFU") (pintype "no_connect"))
    (pad "H6" smd circle (at 0.499 -1 90) (size 0.37 0.37) (layers "F.Cu" "F.Paste" "F.Mask")
      (net 465 "unconnected-(U6-RFU-PadH6)") (pinfunction "RFU") (pintype "no_connect"))
    (pad "H7" smd circle (at 1.499 -1 90) (size 0.37 0.37) (layers "F.Cu" "F.Paste" "F.Mask")
      (net 466 "unconnected-(U6-RFU-PadH7)") (pinfunction "RFU") (pintype "no_connect"))
    (pad "H8" smd circle (at 2.499 -1 90) (size 0.37 0.37) (layers "F.Cu" "F.Paste" "F.Mask")
      (net 2 "VCC3V3") (pinfunction "VCCQ") (pintype "passive"))
    (pad "H9" smd circle (at 3.499 -1 90) (size 0.37 0.37) (layers "F.Cu" "F.Paste" "F.Mask")
      (net 1 "GND") (pinfunction "VSSQ") (pintype "passive"))
    (pad "J2" smd circle (at -3.5 0 90) (size 0.37 0.37) (layers "F.Cu" "F.Paste" "F.Mask")
      (net 467 "unconnected-(U6-RFU-PadJ2)") (pinfunction "RFU") (pintype "no_connect"))
    (pad "J3" smd circle (at -2.5 0 90) (size 0.37 0.37) (layers "F.Cu" "F.Paste" "F.Mask")
      (net 468 "unconnected-(U6-RFU-PadJ3)") (pinfunction "RFU") (pintype "no_connect"))
    (pad "J4" smd circle (at -1.5 0 90) (size 0.37 0.37) (layers "F.Cu" "F.Paste" "F.Mask")
      (net 469 "unconnected-(U6-RFU-PadJ4)") (pinfunction "RFU") (pintype "no_connect"))
    (pad "J5" smd circle (at -0.5 0 90) (size 0.37 0.37) (layers "F.Cu" "F.Paste" "F.Mask")
      (net 1 "GND") (pinfunction "VSS") (pintype "passive"))
    (pad "J6" smd circle (at 0.499 0 90) (size 0.37 0.37) (layers "F.Cu" "F.Paste" "F.Mask")
      (net 470 "unconnected-(U6-RFU-PadJ6)") (pinfunction "RFU") (pintype "no_connect"))
    (pad "J7" smd circle (at 1.499 0 90) (size 0.37 0.37) (layers "F.Cu" "F.Paste" "F.Mask")
      (net 471 "unconnected-(U6-RFU-PadJ7)") (pinfunction "RFU") (pintype "no_connect"))
    (pad "J8" smd circle (at 2.499 0 90) (size 0.37 0.37) (layers "F.Cu" "F.Paste" "F.Mask")
      (net 472 "unconnected-(U6-RFU-PadJ8)") (pinfunction "RFU") (pintype "no_connect"))
    (pad "J9" smd circle (at 3.499 0 90) (size 0.37 0.37) (layers "F.Cu" "F.Paste" "F.Mask")
      (net 473 "unconnected-(U6-RFU-PadJ9)") (pinfunction "RFU") (pintype "no_connect"))
    (pad "K2" smd circle (at -3.5 0.999 90) (size 0.37 0.37) (layers "F.Cu" "F.Paste" "F.Mask")
      (net 279 "MMC_DAT0") (pinfunction "DAT0") (pintype "bidirectional"))
    (pad "K3" smd circle (at -2.5 0.999 90) (size 0.37 0.37) (layers "F.Cu" "F.Paste" "F.Mask")
      (net 281 "MMC_DAT2") (pinfunction "DAT2") (pintype "bidirectional"))
    (pad "K4" smd circle (at -1.5 0.999 90) (size 0.37 0.37) (layers "F.Cu" "F.Paste" "F.Mask")
      (net 474 "unconnected-(U6-RFU-PadK4)") (pinfunction "RFU") (pintype "no_connect"))
    (pad "K5" smd circle (at -0.5 0.999 90) (size 0.37 0.37) (layers "F.Cu" "F.Paste" "F.Mask")
      (net 437 "Net-(U6-DS)") (pinfunction "DS") (pintype "output"))
    (pad "K6" smd circle (at 0.499 0.999 90) (size 0.37 0.37) (layers "F.Cu" "F.Paste" "F.Mask")
      (net 475 "unconnected-(U6-RFU-PadK6)") (pinfunction "RFU") (pintype "no_connect"))
    (pad "K7" smd circle (at 1.499 0.999 90) (size 0.37 0.37) (layers "F.Cu" "F.Paste" "F.Mask")
      (net 476 "unconnected-(U6-RFU-PadK7)") (pinfunction "RFU") (pintype "no_connect"))
    (pad "K8" smd circle (at 2.499 0.999 90) (size 0.37 0.37) (layers "F.Cu" "F.Paste" "F.Mask")
      (net 284 "MMC_DAT5") (pinfunction "DAT5") (pintype "bidirectional"))
    (pad "K9" smd circle (at 3.499 0.999 90) (size 0.37 0.37) (layers "F.Cu" "F.Paste" "F.Mask")
      (net 286 "MMC_DAT7") (pinfunction "DAT7") (pintype "bidirectional"))
    (pad "L2" smd circle (at -3.5 1.999 90) (size 0.37 0.37) (layers "F.Cu" "F.Paste" "F.Mask")
      (net 2 "VCC3V3") (pinfunction "VCCQ") (pintype "passive"))
    (pad "L3" smd circle (at -2.5 1.999 90) (size 0.37 0.37) (layers "F.Cu" "F.Paste" "F.Mask")
      (net 1 "GND") (pinfunction "VSSQ") (pintype "passive"))
    (pad "L4" smd circle (at -1.5 1.999 90) (size 0.37 0.37) (layers "F.Cu" "F.Paste" "F.Mask")
      (net 2 "VCC3V3") (pinfunction "VCCQ") (pintype "passive"))
    (pad "L5" smd circle (at -0.5 1.999 90) (size 0.37 0.37) (layers "F.Cu" "F.Paste" "F.Mask")
      (net 477 "unconnected-(U6-RFU-PadL5)") (pinfunction "RFU") (pintype "no_connect"))
    (pad "L6" smd circle (at 0.499 1.999 90) (size 0.37 0.37) (layers "F.Cu" "F.Paste" "F.Mask")
      (net 478 "unconnected-(U6-RFU-PadL6)") (pinfunction "RFU") (pintype "no_connect"))
    (pad "L7" smd circle (at 1.499 1.999 90) (size 0.37 0.37) (layers "F.Cu" "F.Paste" "F.Mask")
      (net 2 "VCC3V3") (pinfunction "VCCQ") (pintype "passive"))
    (pad "L8" smd circle (at 2.499 1.999 90) (size 0.37 0.37) (layers "F.Cu" "F.Paste" "F.Mask")
      (net 1 "GND") (pinfunction "VSSQ") (pintype "passive"))
    (pad "L9" smd circle (at 3.499 1.999 90) (size 0.37 0.37) (layers "F.Cu" "F.Paste" "F.Mask")
      (net 2 "VCC3V3") (pinfunction "VCCQ") (pintype "passive"))
    (pad "M2" smd circle (at -3.5 2.999 90) (size 0.37 0.37) (layers "F.Cu" "F.Paste" "F.Mask")
      (net 479 "unconnected-(U6-RFU-PadM2)") (pinfunction "RFU") (pintype "no_connect"))
    (pad "M3" smd circle (at -2.5 2.999 90) (size 0.37 0.37) (layers "F.Cu" "F.Paste" "F.Mask")
      (net 480 "unconnected-(U6-RFU-PadM3)") (pinfunction "RFU") (pintype "no_connect"))
    (pad "M4" smd circle (at -1.5 2.999 90) (size 0.37 0.37) (layers "F.Cu" "F.Paste" "F.Mask")
      (net 1 "GND") (pinfunction "VSSQ") (pintype "passive"))
    (pad "M5" smd circle (at -0.5 2.999 90) (size 0.37 0.37) (layers "F.Cu" "F.Paste" "F.Mask")
      (net 377 "MMC_RSTN") (pinfunction "RST_N") (pintype "input"))
    (pad "M6" smd circle (at 0.499 2.999 90) (size 0.37 0.37) (layers "F.Cu" "F.Paste" "F.Mask")
      (net 481 "unconnected-(U6-RFU-PadM6)") (pinfunction "RFU") (pintype "no_connect"))
    (pad "M7" smd circle (at 1.499 2.999 90) (size 0.37 0.37) (layers "F.Cu" "F.Paste" "F.Mask")
      (net 1 "GND") (pinfunction "VSSQ") (pintype "passive"))
    (pad "M8" smd circle (at 2.499 2.999 90) (size 0.37 0.37) (layers "F.Cu" "F.Paste" "F.Mask")
      (net 482 "unconnected-(U6-RFU-PadM8)") (pinfunction "RFU") (pintype "no_connect"))
    (pad "M9" smd circle (at 3.499 2.999 90) (size 0.37 0.37) (layers "F.Cu" "F.Paste" "F.Mask")
      (net 483 "unconnected-(U6-RFU-PadM9)") (pinfunction "RFU") (pintype "no_connect"))
    (pad "N2" smd circle (at -3.5 3.999 90) (size 0.37 0.37) (layers "F.Cu" "F.Paste" "F.Mask")
      (net 280 "MMC_DAT1") (pinfunction "DAT1") (pintype "bidirectional"))
    (pad "N3" smd circle (at -2.5 3.999 90) (size 0.37 0.37) (layers "F.Cu" "F.Paste" "F.Mask")
      (net 282 "MMC_DAT3") (pinfunction "DAT3") (pintype "bidirectional"))
    (pad "N4" smd circle (at -1.5 3.999 90) (size 0.37 0.37) (layers "F.Cu" "F.Paste" "F.Mask")
      (net 484 "unconnected-(U6-RFU-PadN4)") (pinfunction "RFU") (pintype "no_connect"))
    (pad "N5" smd circle (at -0.5 3.999 90) (size 0.37 0.37) (layers "F.Cu" "F.Paste" "F.Mask")
      (net 485 "unconnected-(U6-RFU-PadN5)") (pinfunction "RFU") (pintype "no_connect"))
    (pad "N6" smd circle (at 0.499 3.999 90) (size 0.37 0.37) (layers "F.Cu" "F.Paste" "F.Mask")
      (net 486 "unconnected-(U6-RFU-PadN6)") (pinfunction "RFU") (pintype "no_connect"))
    (pad "N7" smd circle (at 1.499 3.999 90) (size 0.37 0.37) (layers "F.Cu" "F.Paste" "F.Mask")
      (net 487 "unconnected-(U6-RFU-PadN7)") (pinfunction "RFU") (pintype "no_connect"))
    (pad "N8" smd circle (at 2.499 3.999 90) (size 0.37 0.37) (layers "F.Cu" "F.Paste" "F.Mask")
      (net 283 "MMC_DAT4") (pinfunction "DAT4") (pintype "bidirectional"))
    (pad "N9" smd circle (at 3.499 3.999 90) (size 0.37 0.37) (layers "F.Cu" "F.Paste" "F.Mask")
      (net 285 "MMC_DAT6") (pinfunction "DAT6") (pintype "bidirectional"))
    (pad "P2" smd circle (at -3.5 4.999 90) (size 0.37 0.37) (layers "F.Cu" "F.Paste" "F.Mask")
      (net 1 "GND") (pinfunction "VSSQ") (pintype "passive"))
    (pad "P3" smd circle (at -2.5 4.999 90) (size 0.37 0.37) (layers "F.Cu" "F.Paste" "F.Mask")
      (net 2 "VCC3V3") (pinfunction "VCCQ") (pintype "passive"))
    (pad "P4" smd circle (at -1.5 4.999 90) (size 0.37 0.37) (layers "F.Cu" "F.Paste" "F.Mask")
      (net 488 "unconnected-(U6-RFU-PadP4)") (pinfunction "RFU") (pintype "no_connect"))
    (pad "P5" smd circle (at -0.5 4.999 90) (size 0.37 0.37) (layers "F.Cu" "F.Paste" "F.Mask")
      (net 287 "MMC_CMD") (pinfunction "CMD") (pintype "bidirectional"))
    (pad "P6" smd circle (at 0.499 4.999 90) (size 0.37 0.37) (layers "F.Cu" "F.Paste" "F.Mask")
      (net 403 "Net-(U6-CLK)") (pinfunction "CLK") (pintype "input"))
    (pad "P7" smd circle (at 1.499 4.999 90) (size 0.37 0.37) (layers "F.Cu" "F.Paste" "F.Mask")
      (net 489 "unconnected-(U6-RFU-PadP7)") (pinfunction "RFU") (pintype "no_connect"))
    (pad "P8" smd circle (at 2.499 4.999 90) (size 0.37 0.37) (layers "F.Cu" "F.Paste" "F.Mask")
      (net 2 "VCC3V3") (pinfunction "VCCQ") (pintype "passive"))
    (pad "P9" smd circle (at 3.499 4.999 90) (size 0.37 0.37) (layers "F.Cu" "F.Paste" "F.Mask")
      (net 1 "GND") (pinfunction "VSSQ") (pintype "passive"))
    (pad "T1" smd circle (at -4.5 6.998 90) (size 0.37 0.37) (layers "F.Cu" "F.Paste" "F.Mask")
      (net 490 "unconnected-(U6-NC-PadT1)") (pinfunction "NC") (pintype "no_connect"))
    (pad "T10" smd circle (at 4.499 6.998 90) (size 0.37 0.37) (layers "F.Cu" "F.Paste" "F.Mask")
      (net 491 "unconnected-(U6-NC-PadT10)") (pinfunction "NC") (pintype "no_connect"))
    (pad "U1" smd circle (at -4.5 7.998 90) (size 0.37 0.37) (layers "F.Cu" "F.Paste" "F.Mask")
      (net 492 "unconnected-(U6-NC-PadU1)") (pinfunction "NC") (pintype "no_connect"))
    (pad "U2" smd circle (at -3.5 7.998 90) (size 0.37 0.37) (layers "F.Cu" "F.Paste" "F.Mask")
      (net 493 "unconnected-(U6-NC-PadU2)") (pinfunction "NC") (pintype "no_connect"))
    (pad "U9" smd circle (at 3.499 7.998 90) (size 0.37 0.37) (layers "F.Cu" "F.Paste" "F.Mask")
      (net 494 "unconnected-(U6-NC-PadU9)") (pinfunction "NC") (pintype "no_connect"))
    (pad "U10" smd circle (at 4.499 7.998 90) (size 0.37 0.37) (layers "F.Cu" "F.Paste" "F.Mask")
      (net 495 "unconnected-(U6-NC-PadU10)") (pinfunction "NC") (pintype "no_connect"))
  )
)
